(kicad_pcb
	(version 20260206)
	(generator "pcbnew")
	(generator_version "10.0")
	(general
		(thickness 1.6)
		(legacy_teardrops no)
	)
	(paper "A4")
	(title_block
		(title "15969-1a.1015WZS0858.brd")
		(comment 1 "Tioga Pass / footprints 233-239 of 295")
	)
	(layers
		(0 "F.Cu" signal "TOP")
		(4 "In1.Cu" signal "L2GND")
		(6 "In2.Cu" signal "L3")
		(8 "In3.Cu" signal "L4")
		(10 "In4.Cu" signal "L5GND")
		(2 "B.Cu" signal "BOTTOM")
		(9 "F.Adhes" user "F.Adhesive")
		(11 "B.Adhes" user "B.Adhesive")
		(13 "F.Paste" user "Package Geometry/Pastemask Top")
		(15 "B.Paste" user "Package Geometry/Pastemask Bottom")
		(5 "F.SilkS" user "Ref Des/Silkscreen Top")
		(7 "B.SilkS" user "Ref Des/Silkscreen Bottom")
		(1 "F.Mask" user "Board Geometry/Soldermask Top")
		(3 "B.Mask" user "Board Geometry/Soldermask Bottom")
		(17 "Dwgs.User" user "User.Drawings")
		(19 "Cmts.User" user "User.Comments")
		(21 "Eco1.User" user "User.Eco1")
		(23 "Eco2.User" user "User.Eco2")
		(25 "Edge.Cuts" user "Board Geometry/Outline")
		(27 "Margin" user)
		(31 "F.CrtYd" user "Package Geometry/Place Bound Top")
		(29 "B.CrtYd" user "Package Geometry/Place Bound Bottom")
		(35 "F.Fab" user "Ref Des/Assembly Top")
		(33 "B.Fab" user "Ref Des/Assembly Bottom")
	)
	(footprint ""
		(layer "B.Cu")
		(at 105.0544 3.3782 180)
		(property "Reference" "R9"
			(at 0 0 0)
			(layer "B.SilkS")
			(hide yes)
			(effects
				(font
					(size 1.27 1.27)
				)
				(justify mirror)
			)
		)
		(property "Value" "10KR2F-2-GP"
			(at -0.064008 -3.993896 180)
			(unlocked yes)
			(layer "B.Fab")
			(hide yes)
			(effects
				(font
					(size 1.016 1.016)
					(thickness 0.1524)
				)
				(justify mirror)
			)
		)
		(property "Device Type" "R402H16"
			(at -0.064008 -5.517896 180)
			(unlocked yes)
			(layer "B.Fab")
			(hide yes)
			(effects
				(font
					(size 1.016 1.016)
					(thickness 0.1524)
				)
				(justify mirror)
			)
		)
		(duplicate_pad_numbers_are_jumpers no)
		(fp_line
			(start 0.508 -0.9398)
			(end 0.508 0.9398)
			(stroke
				(width 0.1524)
				(type default)
			)
			(layer "B.SilkS")
		)
		(fp_line
			(start -0.508 -0.9398)
			(end 0.508 -0.9398)
			(stroke
				(width 0.1524)
				(type default)
			)
			(layer "B.SilkS")
		)
		(fp_rect
			(start 0.508 0.9398)
			(end -0.508 -0.9398)
			(stroke
				(width 0)
				(type default)
			)
			(fill no)
			(layer "B.CrtYd")
		)
		(fp_rect
			(start 0.508 0.9398)
			(end -0.508 -0.9398)
			(stroke
				(width 0)
				(type default)
			)
			(fill no)
			(layer "B.Fab")
		)
		(pad "1" smd custom
			(at 0 -0.4445)
			(size 0.1397 0.1397)
			(layers "B.Cu" "B.Mask" "B.Paste")
			(net "IRQ_OOB_MGMT_RISER_ALERT_N")
			(options
				(clearance outline)
				(anchor circle)
			)
			(primitives
				(gr_poly
					(pts
						(arc
							(start -0.1778 0.2794)
							(mid -0.249642 0.249642)
							(end -0.2794 0.1778)
						)
						(arc
							(start -0.2794 -0.1778)
							(mid -0.249642 -0.249642)
							(end -0.1778 -0.2794)
						)
						(arc
							(start 0.1778 -0.2794)
							(mid 0.249642 -0.249642)
							(end 0.2794 -0.1778)
						)
						(arc
							(start 0.2794 0.1778)
							(mid 0.249642 0.249642)
							(end 0.1778 0.2794)
						)
					)
					(width 0)
					(fill yes)
				)
			)
		)
		(pad "2" smd custom
			(at 0 0.4445)
			(size 0.1397 0.1397)
			(layers "B.Cu" "B.Mask" "B.Paste")
			(net "P3V3_STBY")
			(options
				(clearance outline)
				(anchor circle)
			)
			(primitives
				(gr_poly
					(pts
						(arc
							(start -0.1778 0.2794)
							(mid -0.249642 0.249642)
							(end -0.2794 0.1778)
						)
						(arc
							(start -0.2794 -0.1778)
							(mid -0.249642 -0.249642)
							(end -0.1778 -0.2794)
						)
						(arc
							(start 0.1778 -0.2794)
							(mid 0.249642 -0.249642)
							(end 0.2794 -0.1778)
						)
						(arc
							(start 0.2794 0.1778)
							(mid 0.249642 0.249642)
							(end 0.1778 0.2794)
						)
					)
					(width 0)
					(fill yes)
				)
			)
		)
	)
	(footprint ""
		(layer "B.Cu")
		(at 19.0373 -13.9192 180)
		(property "Reference" "PC13"
			(at 0 0 0)
			(layer "B.SilkS")
			(hide yes)
			(effects
				(font
					(size 1.27 1.27)
				)
				(justify mirror)
			)
		)
		(property "Value" "SC2D2U10V3KX-2GP-U1"
			(at 0 -2.8194 180)
			(unlocked yes)
			(layer "B.Fab")
			(hide yes)
			(effects
				(font
					(size 1.016 1.016)
					(thickness 0.1524)
				)
				(justify mirror)
			)
		)
		(property "Device Type" "C603H40"
			(at 0 -4.3434 180)
			(unlocked yes)
			(layer "B.Fab")
			(hide yes)
			(effects
				(font
					(size 1.016 1.016)
					(thickness 0.1524)
				)
				(justify mirror)
			)
		)
		(duplicate_pad_numbers_are_jumpers no)
		(fp_line
			(start -0.508 0)
			(end 0.508 0)
			(stroke
				(width 0.2032)
				(type default)
			)
			(layer "B.SilkS")
		)
		(fp_rect
			(start 0.5842 1.3335)
			(end -0.5842 -1.3335)
			(stroke
				(width 0)
				(type default)
			)
			(fill no)
			(layer "B.CrtYd")
		)
		(fp_rect
			(start 0.5842 1.3335)
			(end -0.5842 -1.3335)
			(stroke
				(width 0)
				(type default)
			)
			(fill no)
			(layer "B.Fab")
		)
		(pad "1" smd custom
			(at 0 -0.762)
			(size 0.2159 0.2159)
			(layers "B.Cu" "B.Mask" "B.Paste")
			(net "P3V3_EN")
			(options
				(clearance outline)
				(anchor circle)
			)
			(primitives
				(gr_poly
					(pts
						(arc
							(start -0.3302 0.4318)
							(mid -0.402042 0.402042)
							(end -0.4318 0.3302)
						)
						(arc
							(start -0.4318 -0.3302)
							(mid -0.402042 -0.402042)
							(end -0.3302 -0.4318)
						)
						(arc
							(start 0.3302 -0.4318)
							(mid 0.402042 -0.402042)
							(end 0.4318 -0.3302)
						)
						(arc
							(start 0.4318 0.3302)
							(mid 0.402042 0.402042)
							(end 0.3302 0.4318)
						)
					)
					(width 0)
					(fill yes)
				)
			)
		)
		(pad "2" smd custom
			(at 0 0.762)
			(size 0.2159 0.2159)
			(layers "B.Cu" "B.Mask" "B.Paste")
			(net "GND")
			(options
				(clearance outline)
				(anchor circle)
			)
			(primitives
				(gr_poly
					(pts
						(arc
							(start -0.3302 0.4318)
							(mid -0.402042 0.402042)
							(end -0.4318 0.3302)
						)
						(arc
							(start -0.4318 -0.3302)
							(mid -0.402042 -0.402042)
							(end -0.3302 -0.4318)
						)
						(arc
							(start 0.3302 -0.4318)
							(mid 0.402042 -0.402042)
							(end 0.4318 -0.3302)
						)
						(arc
							(start 0.4318 0.3302)
							(mid 0.402042 0.402042)
							(end 0.3302 0.4318)
						)
					)
					(width 0)
					(fill yes)
				)
			)
		)
	)
	(footprint ""
		(layer "B.Cu")
		(at 25.6032 -7.6708 180)
		(property "Reference" "PC12"
			(at 0 0 0)
			(layer "B.SilkS")
			(hide yes)
			(effects
				(font
					(size 1.27 1.27)
				)
				(justify mirror)
			)
		)
		(property "Value" "SC2D2U10V3KX-2GP-U1"
			(at 0 -2.8194 180)
			(unlocked yes)
			(layer "B.Fab")
			(hide yes)
			(effects
				(font
					(size 1.016 1.016)
					(thickness 0.1524)
				)
				(justify mirror)
			)
		)
		(property "Device Type" "C603H40"
			(at 0 -4.3434 180)
			(unlocked yes)
			(layer "B.Fab")
			(hide yes)
			(effects
				(font
					(size 1.016 1.016)
					(thickness 0.1524)
				)
				(justify mirror)
			)
		)
		(duplicate_pad_numbers_are_jumpers no)
		(fp_line
			(start -0.508 0)
			(end 0.508 0)
			(stroke
				(width 0.2032)
				(type default)
			)
			(layer "B.SilkS")
		)
		(fp_rect
			(start 0.5842 1.3335)
			(end -0.5842 -1.3335)
			(stroke
				(width 0)
				(type default)
			)
			(fill no)
			(layer "B.CrtYd")
		)
		(fp_rect
			(start 0.5842 1.3335)
			(end -0.5842 -1.3335)
			(stroke
				(width 0)
				(type default)
			)
			(fill no)
			(layer "B.Fab")
		)
		(pad "1" smd custom
			(at 0 -0.762)
			(size 0.2159 0.2159)
			(layers "B.Cu" "B.Mask" "B.Paste")
			(net "P3V3_VCC")
			(options
				(clearance outline)
				(anchor circle)
			)
			(primitives
				(gr_poly
					(pts
						(arc
							(start -0.3302 0.4318)
							(mid -0.402042 0.402042)
							(end -0.4318 0.3302)
						)
						(arc
							(start -0.4318 -0.3302)
							(mid -0.402042 -0.402042)
							(end -0.3302 -0.4318)
						)
						(arc
							(start 0.3302 -0.4318)
							(mid 0.402042 -0.402042)
							(end 0.4318 -0.3302)
						)
						(arc
							(start 0.4318 0.3302)
							(mid 0.402042 0.402042)
							(end 0.3302 0.4318)
						)
					)
					(width 0)
					(fill yes)
				)
			)
		)
		(pad "2" smd custom
			(at 0 0.762)
			(size 0.2159 0.2159)
			(layers "B.Cu" "B.Mask" "B.Paste")
			(net "GND")
			(options
				(clearance outline)
				(anchor circle)
			)
			(primitives
				(gr_poly
					(pts
						(arc
							(start -0.3302 0.4318)
							(mid -0.402042 0.402042)
							(end -0.4318 0.3302)
						)
						(arc
							(start -0.4318 -0.3302)
							(mid -0.402042 -0.402042)
							(end -0.3302 -0.4318)
						)
						(arc
							(start 0.3302 -0.4318)
							(mid 0.402042 -0.402042)
							(end 0.4318 -0.3302)
						)
						(arc
							(start 0.4318 0.3302)
							(mid 0.402042 0.402042)
							(end 0.3302 0.4318)
						)
					)
					(width 0)
					(fill yes)
				)
			)
		)
	)
	(footprint ""
		(layer "B.Cu")
		(at 41.7195 3.0226 -90)
		(property "Reference" "R51"
			(at 0 0 90)
			(layer "B.SilkS")
			(hide yes)
			(effects
				(font
					(size 1.27 1.27)
				)
				(justify mirror)
			)
		)
		(property "Value" "0R2F-1-GP"
			(at -0.064008 -3.993896 270)
			(unlocked yes)
			(layer "B.Fab")
			(hide yes)
			(effects
				(font
					(size 1.016 1.016)
					(thickness 0.1524)
				)
				(justify mirror)
			)
		)
		(property "Device Type" "R402H16"
			(at -0.064008 -5.517896 270)
			(unlocked yes)
			(layer "B.Fab")
			(hide yes)
			(effects
				(font
					(size 1.016 1.016)
					(thickness 0.1524)
				)
				(justify mirror)
			)
		)
		(duplicate_pad_numbers_are_jumpers no)
		(fp_line
			(start -0.508 -0.9398)
			(end 0.508 -0.9398)
			(stroke
				(width 0.1524)
				(type default)
			)
			(layer "B.SilkS")
		)
		(fp_line
			(start 0.508 -0.9398)
			(end 0.508 0.9398)
			(stroke
				(width 0.1524)
				(type default)
			)
			(layer "B.SilkS")
		)
		(fp_rect
			(start 0.508 0.9398)
			(end -0.508 -0.9398)
			(stroke
				(width 0)
				(type default)
			)
			(fill no)
			(layer "B.CrtYd")
		)
		(fp_rect
			(start 0.508 0.9398)
			(end -0.508 -0.9398)
			(stroke
				(width 0)
				(type default)
			)
			(fill no)
			(layer "B.Fab")
		)
		(pad "1" smd custom
			(at 0 -0.4445 90)
			(size 0.1397 0.1397)
			(layers "B.Cu" "B.Mask" "B.Paste")
			(net "SMDAT_PCH_R")
			(options
				(clearance outline)
				(anchor circle)
			)
			(primitives
				(gr_poly
					(pts
						(arc
							(start -0.1778 0.2794)
							(mid -0.249642 0.249642)
							(end -0.2794 0.1778)
						)
						(arc
							(start -0.2794 -0.1778)
							(mid -0.249642 -0.249642)
							(end -0.1778 -0.2794)
						)
						(arc
							(start 0.1778 -0.2794)
							(mid 0.249642 -0.249642)
							(end 0.2794 -0.1778)
						)
						(arc
							(start 0.2794 0.1778)
							(mid 0.249642 0.249642)
							(end 0.1778 0.2794)
						)
					)
					(width 0)
					(fill yes)
				)
			)
		)
		(pad "2" smd custom
			(at 0 0.4445 90)
			(size 0.1397 0.1397)
			(layers "B.Cu" "B.Mask" "B.Paste")
			(net "SMB_HOST_STBY_LVC3_SDA_R5")
			(options
				(clearance outline)
				(anchor circle)
			)
			(primitives
				(gr_poly
					(pts
						(arc
							(start -0.1778 0.2794)
							(mid -0.249642 0.249642)
							(end -0.2794 0.1778)
						)
						(arc
							(start -0.2794 -0.1778)
							(mid -0.249642 -0.249642)
							(end -0.1778 -0.2794)
						)
						(arc
							(start 0.1778 -0.2794)
							(mid 0.249642 -0.249642)
							(end 0.2794 -0.1778)
						)
						(arc
							(start 0.2794 0.1778)
							(mid 0.249642 0.249642)
							(end 0.1778 0.2794)
						)
					)
					(width 0)
					(fill yes)
				)
			)
		)
	)
	(footprint ""
		(layer "B.Cu")
		(at 37.9603 0.3048 -90)
		(property "Reference" "R202"
			(at 0 0 90)
			(layer "B.SilkS")
			(hide yes)
			(effects
				(font
					(size 1.27 1.27)
				)
				(justify mirror)
			)
		)
		(property "Value" "4K7R2F-GP"
			(at -0.064008 -3.993896 270)
			(unlocked yes)
			(layer "B.Fab")
			(hide yes)
			(effects
				(font
					(size 1.016 1.016)
					(thickness 0.1524)
				)
				(justify mirror)
			)
		)
		(property "Device Type" "R402H16"
			(at -0.064008 -5.517896 270)
			(unlocked yes)
			(layer "B.Fab")
			(hide yes)
			(effects
				(font
					(size 1.016 1.016)
					(thickness 0.1524)
				)
				(justify mirror)
			)
		)
		(duplicate_pad_numbers_are_jumpers no)
		(fp_line
			(start -0.508 -0.9398)
			(end 0.508 -0.9398)
			(stroke
				(width 0.1524)
				(type default)
			)
			(layer "B.SilkS")
		)
		(fp_line
			(start 0.508 -0.9398)
			(end 0.508 0.9398)
			(stroke
				(width 0.1524)
				(type default)
			)
			(layer "B.SilkS")
		)
		(fp_rect
			(start 0.508 0.9398)
			(end -0.508 -0.9398)
			(stroke
				(width 0)
				(type default)
			)
			(fill no)
			(layer "B.CrtYd")
		)
		(fp_rect
			(start 0.508 0.9398)
			(end -0.508 -0.9398)
			(stroke
				(width 0)
				(type default)
			)
			(fill no)
			(layer "B.Fab")
		)
		(pad "1" smd custom
			(at 0 -0.4445 90)
			(size 0.1397 0.1397)
			(layers "B.Cu" "B.Mask" "B.Paste")
			(net "P3V3_STBY")
			(options
				(clearance outline)
				(anchor circle)
			)
			(primitives
				(gr_poly
					(pts
						(arc
							(start -0.1778 0.2794)
							(mid -0.249642 0.249642)
							(end -0.2794 0.1778)
						)
						(arc
							(start -0.2794 -0.1778)
							(mid -0.249642 -0.249642)
							(end -0.1778 -0.2794)
						)
						(arc
							(start 0.1778 -0.2794)
							(mid 0.249642 -0.249642)
							(end 0.2794 -0.1778)
						)
						(arc
							(start 0.2794 0.1778)
							(mid 0.249642 0.249642)
							(end 0.1778 0.2794)
						)
					)
					(width 0)
					(fill yes)
				)
			)
		)
		(pad "2" smd custom
			(at 0 0.4445 90)
			(size 0.1397 0.1397)
			(layers "B.Cu" "B.Mask" "B.Paste")
			(net "SMDAT_PCH_R")
			(options
				(clearance outline)
				(anchor circle)
			)
			(primitives
				(gr_poly
					(pts
						(arc
							(start -0.1778 0.2794)
							(mid -0.249642 0.249642)
							(end -0.2794 0.1778)
						)
						(arc
							(start -0.2794 -0.1778)
							(mid -0.249642 -0.249642)
							(end -0.1778 -0.2794)
						)
						(arc
							(start 0.1778 -0.2794)
							(mid 0.249642 -0.249642)
							(end 0.2794 -0.1778)
						)
						(arc
							(start 0.2794 0.1778)
							(mid 0.249642 0.249642)
							(end 0.1778 0.2794)
						)
					)
					(width 0)
					(fill yes)
				)
			)
		)
	)
	(footprint ""
		(layer "B.Cu")
		(at 35.9791 0.2921 90)
		(property "Reference" "R201"
			(at 0 0 90)
			(layer "B.SilkS")
			(hide yes)
			(effects
				(font
					(size 1.27 1.27)
				)
				(justify mirror)
			)
		)
		(property "Value" "4K7R2F-GP"
			(at -0.064008 -3.993896 90)
			(unlocked yes)
			(layer "B.Fab")
			(hide yes)
			(effects
				(font
					(size 1.016 1.016)
					(thickness 0.1524)
				)
				(justify mirror)
			)
		)
		(property "Device Type" "R402H16"
			(at -0.064008 -5.517896 90)
			(unlocked yes)
			(layer "B.Fab")
			(hide yes)
			(effects
				(font
					(size 1.016 1.016)
					(thickness 0.1524)
				)
				(justify mirror)
			)
		)
		(duplicate_pad_numbers_are_jumpers no)
		(fp_line
			(start 0.508 -0.9398)
			(end 0.508 0.9398)
			(stroke
				(width 0.1524)
				(type default)
			)
			(layer "B.SilkS")
		)
		(fp_line
			(start -0.508 -0.9398)
			(end 0.508 -0.9398)
			(stroke
				(width 0.1524)
				(type default)
			)
			(layer "B.SilkS")
		)
		(fp_rect
			(start 0.508 0.9398)
			(end -0.508 -0.9398)
			(stroke
				(width 0)
				(type default)
			)
			(fill no)
			(layer "B.CrtYd")
		)
		(fp_rect
			(start 0.508 0.9398)
			(end -0.508 -0.9398)
			(stroke
				(width 0)
				(type default)
			)
			(fill no)
			(layer "B.Fab")
		)
		(pad "1" smd custom
			(at 0 -0.4445 270)
			(size 0.1397 0.1397)
			(layers "B.Cu" "B.Mask" "B.Paste")
			(net "P3V3_STBY")
			(options
				(clearance outline)
				(anchor circle)
			)
			(primitives
				(gr_poly
					(pts
						(arc
							(start -0.1778 0.2794)
							(mid -0.249642 0.249642)
							(end -0.2794 0.1778)
						)
						(arc
							(start -0.2794 -0.1778)
							(mid -0.249642 -0.249642)
							(end -0.1778 -0.2794)
						)
						(arc
							(start 0.1778 -0.2794)
							(mid 0.249642 -0.249642)
							(end 0.2794 -0.1778)
						)
						(arc
							(start 0.2794 0.1778)
							(mid 0.249642 0.249642)
							(end 0.1778 0.2794)
						)
					)
					(width 0)
					(fill yes)
				)
			)
		)
		(pad "2" smd custom
			(at 0 0.4445 270)
			(size 0.1397 0.1397)
			(layers "B.Cu" "B.Mask" "B.Paste")
			(net "SMCLK_PCH_R")
			(options
				(clearance outline)
				(anchor circle)
			)
			(primitives
				(gr_poly
					(pts
						(arc
							(start -0.1778 0.2794)
							(mid -0.249642 0.249642)
							(end -0.2794 0.1778)
						)
						(arc
							(start -0.2794 -0.1778)
							(mid -0.249642 -0.249642)
							(end -0.1778 -0.2794)
						)
						(arc
							(start 0.1778 -0.2794)
							(mid 0.249642 -0.249642)
							(end 0.2794 -0.1778)
						)
						(arc
							(start 0.2794 0.1778)
							(mid 0.249642 0.249642)
							(end 0.1778 0.2794)
						)
					)
					(width 0)
					(fill yes)
				)
			)
		)
	)
	(footprint ""
		(layer "B.Cu")
		(at 16.8148 -10.0076 180)
		(property "Reference" "PC15"
			(at 0 0 0)
			(layer "B.SilkS")
			(hide yes)
			(effects
				(font
					(size 1.27 1.27)
				)
				(justify mirror)
			)
		)
		(property "Value" "SCD1U16V2KX-3GP"
			(at -1.1811 -2.7051 180)
			(unlocked yes)
			(layer "B.Fab")
			(hide yes)
			(effects
				(font
					(size 1.016 1.016)
					(thickness 0.1524)
				)
				(justify mirror)
			)
		)
		(property "Device Type" "C402H22"
			(at -1.1811 -4.2291 180)
			(unlocked yes)
			(layer "B.Fab")
			(hide yes)
			(effects
				(font
					(size 1.016 1.016)
					(thickness 0.1524)
				)
				(justify mirror)
			)
		)
		(duplicate_pad_numbers_are_jumpers no)
		(fp_rect
			(start 0.4318 0.9525)
			(end -0.4318 -0.9525)
			(stroke
				(width 0)
				(type default)
			)
			(fill no)
			(layer "B.CrtYd")
		)
		(fp_rect
			(start 0.4318 0.9525)
			(end -0.4318 -0.9525)
			(stroke
				(width 0)
				(type default)
			)
			(fill no)
			(layer "B.Fab")
		)
		(pad "1" smd custom
			(at 0 -0.4445)
			(size 0.1524 0.1524)
			(layers "B.Cu" "B.Mask" "B.Paste")
			(net "P3V3_TRK")
			(options
				(clearance outline)
				(anchor circle)
			)
			(primitives
				(gr_poly
					(pts
						(arc
							(start 0.3048 0.2032)
							(mid 0.275042 0.275042)
							(end 0.2032 0.3048)
						)
						(arc
							(start -0.2032 0.3048)
							(mid -0.275042 0.275042)
							(end -0.3048 0.2032)
						)
						(arc
							(start -0.3048 -0.2032)
							(mid -0.275042 -0.275042)
							(end -0.2032 -0.3048)
						)
						(arc
							(start 0.2032 -0.3048)
							(mid 0.275042 -0.275042)
							(end 0.3048 -0.2032)
						)
					)
					(width 0)
					(fill yes)
				)
			)
		)
		(pad "2" smd custom
			(at 0 0.4445)
			(size 0.1524 0.1524)
			(layers "B.Cu" "B.Mask" "B.Paste")
			(net "GND")
			(options
				(clearance outline)
				(anchor circle)
			)
			(primitives
				(gr_poly
					(pts
						(arc
							(start 0.3048 0.2032)
							(mid 0.275042 0.275042)
							(end 0.2032 0.3048)
						)
						(arc
							(start -0.2032 0.3048)
							(mid -0.275042 0.275042)
							(end -0.3048 0.2032)
						)
						(arc
							(start -0.3048 -0.2032)
							(mid -0.275042 -0.275042)
							(end -0.2032 -0.3048)
						)
						(arc
							(start 0.2032 -0.3048)
							(mid 0.275042 -0.275042)
							(end 0.3048 -0.2032)
						)
					)
					(width 0)
					(fill yes)
				)
			)
		)
	)
)
